G04*
G04 #@! TF.GenerationSoftware,Altium Limited,Altium Designer,23.0.1 (38)*
G04*
G04 Layer_Physical_Order=3*
G04 Layer_Color=65280*
%FSLAX25Y25*%
%MOIN*%
G70*
G04*
G04 #@! TF.SameCoordinates,C48E81DB-6E20-4E2D-80E6-7C5AFAA1A21F*
G04*
G04*
G04 #@! TF.FilePolarity,Positive*
G04*
G01*
G75*
%ADD12C,0.02000*%
%ADD14C,0.01000*%
%ADD19C,0.00500*%
%ADD24C,0.00800*%
%ADD240C,0.06102*%
%ADD241C,0.10000*%
%ADD250C,0.01600*%
G36*
X142520Y-60630D02*
X344882D01*
Y-88792D01*
X344711Y-89430D01*
Y-90352D01*
X344882Y-90990D01*
Y-94095D01*
X348819D01*
Y-118898D01*
X383465D01*
Y-128887D01*
X336418D01*
X325837Y-118306D01*
Y-110236D01*
X325837Y-110236D01*
X325728Y-109690D01*
X325419Y-109227D01*
X325197Y-109005D01*
Y-106299D01*
X324410D01*
Y-83071D01*
X175197D01*
Y-103150D01*
X101181D01*
Y-81496D01*
X54331D01*
Y-34646D01*
X110122D01*
X110666Y-34871D01*
X111382D01*
X111925Y-34646D01*
X142520D01*
Y-60630D01*
D02*
G37*
G36*
X577165Y-79245D02*
X577148Y-79252D01*
X576642Y-79759D01*
X576368Y-80420D01*
Y-81136D01*
X576642Y-81798D01*
X576420Y-82284D01*
X396457D01*
Y-110236D01*
X369291D01*
Y-62598D01*
X577165D01*
Y-79245D01*
D02*
G37*
G36*
X583071Y-146457D02*
Y-177838D01*
X582846Y-178382D01*
Y-179098D01*
X583071Y-179642D01*
Y-181890D01*
X605512D01*
Y-203150D01*
X585039D01*
Y-192520D01*
X570193D01*
X569649Y-192295D01*
X569291D01*
Y-131496D01*
X570866D01*
Y-128740D01*
X583071D01*
Y-146457D01*
D02*
G37*
G36*
X692520Y-290158D02*
X642126D01*
Y-174409D01*
X648425D01*
Y-151969D01*
X692520D01*
Y-290158D01*
D02*
G37*
G36*
X91732Y-291339D02*
X72835D01*
Y-278740D01*
X91732D01*
Y-291339D01*
D02*
G37*
%LPC*%
G36*
X101933Y-40326D02*
X101217D01*
X100555Y-40600D01*
X100049Y-41106D01*
X99775Y-41768D01*
Y-42484D01*
X100049Y-43146D01*
X100555Y-43652D01*
X101217Y-43926D01*
X101933D01*
X102594Y-43652D01*
X103101Y-43146D01*
X103375Y-42484D01*
Y-41768D01*
X103101Y-41106D01*
X102594Y-40600D01*
X101933Y-40326D01*
D02*
G37*
G36*
X99768Y-48249D02*
X99051D01*
X98390Y-48523D01*
X97883Y-49029D01*
X97610Y-49691D01*
Y-50407D01*
X97883Y-51069D01*
X98390Y-51575D01*
X99051Y-51849D01*
X99768D01*
X100429Y-51575D01*
X100935Y-51069D01*
X101209Y-50407D01*
Y-49691D01*
X100935Y-49029D01*
X100429Y-48523D01*
X99768Y-48249D01*
D02*
G37*
G36*
X66303D02*
X65587D01*
X64925Y-48523D01*
X64419Y-49029D01*
X64145Y-49691D01*
Y-50407D01*
X64419Y-51069D01*
X64925Y-51575D01*
X65587Y-51849D01*
X66303D01*
X66965Y-51575D01*
X67471Y-51069D01*
X67745Y-50407D01*
Y-49691D01*
X67471Y-49029D01*
X66965Y-48523D01*
X66303Y-48249D01*
D02*
G37*
G36*
X83282Y-51490D02*
X82289D01*
X81372Y-51870D01*
X80669Y-52572D01*
X80289Y-53489D01*
Y-54482D01*
X80669Y-55400D01*
X81372Y-56102D01*
X82289Y-56482D01*
X83282D01*
X84199Y-56102D01*
X84901Y-55400D01*
X85281Y-54482D01*
Y-53489D01*
X84901Y-52572D01*
X84199Y-51870D01*
X83282Y-51490D01*
D02*
G37*
G36*
X99768Y-56123D02*
X99051D01*
X98390Y-56397D01*
X97883Y-56903D01*
X97610Y-57565D01*
Y-58281D01*
X97883Y-58943D01*
X98390Y-59449D01*
X99051Y-59723D01*
X99768D01*
X100429Y-59449D01*
X100935Y-58943D01*
X101209Y-58281D01*
Y-57565D01*
X100935Y-56903D01*
X100429Y-56397D01*
X99768Y-56123D01*
D02*
G37*
G36*
X66303D02*
X65587D01*
X64925Y-56397D01*
X64419Y-56903D01*
X64145Y-57565D01*
Y-58281D01*
X64419Y-58943D01*
X64925Y-59449D01*
X65587Y-59723D01*
X66303D01*
X66965Y-59449D01*
X67471Y-58943D01*
X67745Y-58281D01*
Y-57565D01*
X67471Y-56903D01*
X66965Y-56397D01*
X66303Y-56123D01*
D02*
G37*
G36*
X99768Y-63997D02*
X99051D01*
X98390Y-64271D01*
X97883Y-64777D01*
X97610Y-65439D01*
Y-66155D01*
X97883Y-66817D01*
X98390Y-67323D01*
X99051Y-67597D01*
X99768D01*
X100429Y-67323D01*
X100935Y-66817D01*
X101209Y-66155D01*
Y-65439D01*
X100935Y-64777D01*
X100429Y-64271D01*
X99768Y-63997D01*
D02*
G37*
G36*
X66303D02*
X65587D01*
X64925Y-64271D01*
X64419Y-64777D01*
X64145Y-65439D01*
Y-66155D01*
X64419Y-66817D01*
X64925Y-67323D01*
X65587Y-67597D01*
X66303D01*
X66965Y-67323D01*
X67471Y-66817D01*
X67745Y-66155D01*
Y-65439D01*
X67471Y-64777D01*
X66965Y-64271D01*
X66303Y-63997D01*
D02*
G37*
G36*
X83282Y-67238D02*
X82289D01*
X81372Y-67618D01*
X80669Y-68320D01*
X80289Y-69237D01*
Y-70230D01*
X80669Y-71148D01*
X81372Y-71850D01*
X82289Y-72230D01*
X83282D01*
X84199Y-71850D01*
X84901Y-71148D01*
X85281Y-70230D01*
Y-69237D01*
X84901Y-68320D01*
X84199Y-67618D01*
X83282Y-67238D01*
D02*
G37*
G36*
X132248Y-70887D02*
X131532D01*
X130870Y-71161D01*
X130364Y-71667D01*
X130090Y-72329D01*
Y-73045D01*
X130364Y-73706D01*
X130870Y-74213D01*
X131532Y-74487D01*
X132248D01*
X132909Y-74213D01*
X133416Y-73706D01*
X133690Y-73045D01*
Y-72329D01*
X133416Y-71667D01*
X132909Y-71161D01*
X132248Y-70887D01*
D02*
G37*
G36*
X130279Y-77776D02*
X129563D01*
X128902Y-78050D01*
X128395Y-78557D01*
X128121Y-79218D01*
Y-79934D01*
X128395Y-80596D01*
X128902Y-81102D01*
X129563Y-81376D01*
X130279D01*
X130941Y-81102D01*
X131447Y-80596D01*
X131721Y-79934D01*
Y-79218D01*
X131447Y-78557D01*
X130941Y-78050D01*
X130279Y-77776D01*
D02*
G37*
G36*
X114531Y-81288D02*
X113815D01*
X113154Y-81562D01*
X112647Y-82069D01*
X112373Y-82730D01*
Y-83446D01*
X112647Y-84108D01*
X113154Y-84614D01*
X113815Y-84888D01*
X114531D01*
X115193Y-84614D01*
X115699Y-84108D01*
X115973Y-83446D01*
Y-82730D01*
X115699Y-82069D01*
X115193Y-81562D01*
X114531Y-81288D01*
D02*
G37*
G36*
X657838Y-162767D02*
X657122D01*
X656461Y-163041D01*
X655954Y-163547D01*
X655680Y-164209D01*
Y-164925D01*
X655954Y-165587D01*
X656461Y-166093D01*
X657122Y-166367D01*
X657838D01*
X658500Y-166093D01*
X659006Y-165587D01*
X659280Y-164925D01*
Y-164209D01*
X659006Y-163547D01*
X658500Y-163041D01*
X657838Y-162767D01*
D02*
G37*
G36*
X668862Y-163161D02*
X668146D01*
X667484Y-163435D01*
X666978Y-163941D01*
X666704Y-164603D01*
Y-165319D01*
X666978Y-165980D01*
X667484Y-166487D01*
X668146Y-166761D01*
X668862D01*
X669524Y-166487D01*
X670030Y-165980D01*
X670304Y-165319D01*
Y-164603D01*
X670030Y-163941D01*
X669524Y-163435D01*
X668862Y-163161D01*
D02*
G37*
G36*
X663350D02*
X662634D01*
X661973Y-163435D01*
X661466Y-163941D01*
X661192Y-164603D01*
Y-165319D01*
X661466Y-165980D01*
X661973Y-166487D01*
X662634Y-166761D01*
X663350D01*
X664012Y-166487D01*
X664518Y-165980D01*
X664792Y-165319D01*
Y-164603D01*
X664518Y-163941D01*
X664012Y-163435D01*
X663350Y-163161D01*
D02*
G37*
G36*
X653114D02*
X652398D01*
X651736Y-163435D01*
X651230Y-163941D01*
X650956Y-164603D01*
Y-165319D01*
X651230Y-165980D01*
X651736Y-166487D01*
X652398Y-166761D01*
X653114D01*
X653776Y-166487D01*
X654282Y-165980D01*
X654556Y-165319D01*
Y-164603D01*
X654282Y-163941D01*
X653776Y-163435D01*
X653114Y-163161D01*
D02*
G37*
G36*
X677523Y-170641D02*
X676807D01*
X676146Y-170915D01*
X675639Y-171421D01*
X675467Y-171836D01*
X674926D01*
X674754Y-171421D01*
X674248Y-170915D01*
X673586Y-170641D01*
X672870D01*
X672209Y-170915D01*
X671702Y-171421D01*
X671428Y-172083D01*
Y-172799D01*
X671702Y-173461D01*
X672209Y-173967D01*
X672870Y-174241D01*
X673586D01*
X674248Y-173967D01*
X674754Y-173461D01*
X674926Y-173046D01*
X675467D01*
X675639Y-173461D01*
X676146Y-173967D01*
X676807Y-174241D01*
X677523D01*
X678185Y-173967D01*
X678691Y-173461D01*
X678965Y-172799D01*
Y-172083D01*
X678691Y-171421D01*
X678185Y-170915D01*
X677523Y-170641D01*
D02*
G37*
G36*
X681854Y-177728D02*
X681138D01*
X680476Y-178002D01*
X679970Y-178508D01*
X679696Y-179169D01*
Y-179886D01*
X679970Y-180547D01*
X680476Y-181053D01*
X681138Y-181328D01*
X681854D01*
X682516Y-181053D01*
X683022Y-180547D01*
X683296Y-179886D01*
Y-179169D01*
X683022Y-178508D01*
X682516Y-178002D01*
X681854Y-177728D01*
D02*
G37*
G36*
X675949Y-194657D02*
X675233D01*
X674571Y-194931D01*
X674065Y-195437D01*
X673791Y-196099D01*
Y-196815D01*
X674065Y-197476D01*
X674420Y-197832D01*
X674368Y-198357D01*
X674341Y-198406D01*
X674177Y-198474D01*
X673671Y-198980D01*
X673397Y-199642D01*
Y-200358D01*
X673671Y-201020D01*
X674177Y-201526D01*
X674839Y-201800D01*
X675555D01*
X676217Y-201526D01*
X676688Y-201055D01*
X676968Y-201036D01*
X677249Y-201055D01*
X677720Y-201526D01*
X678382Y-201800D01*
X679098D01*
X679760Y-201526D01*
X679988Y-201297D01*
X680315Y-201056D01*
X680642Y-201297D01*
X680870Y-201526D01*
X681532Y-201800D01*
X682248D01*
X682909Y-201526D01*
X683416Y-201020D01*
X683690Y-200358D01*
Y-199642D01*
X683416Y-198980D01*
X683187Y-198752D01*
X682945Y-198425D01*
X683187Y-198099D01*
X683416Y-197870D01*
X683690Y-197208D01*
Y-196492D01*
X683416Y-195831D01*
X682909Y-195324D01*
X682248Y-195050D01*
X681532D01*
X680870Y-195324D01*
X680642Y-195553D01*
X680315Y-195795D01*
X679988Y-195553D01*
X679760Y-195324D01*
X679098Y-195050D01*
X678382D01*
X677720Y-195324D01*
X677526Y-195519D01*
X677116Y-195437D01*
X676610Y-194931D01*
X675949Y-194657D01*
D02*
G37*
G36*
X681067Y-210405D02*
X680351D01*
X679689Y-210679D01*
X679183Y-211185D01*
X678909Y-211847D01*
Y-212563D01*
X679183Y-213224D01*
X679689Y-213731D01*
X680351Y-214005D01*
X681067D01*
X681728Y-213731D01*
X682235Y-213224D01*
X682509Y-212563D01*
Y-211847D01*
X682235Y-211185D01*
X681728Y-210679D01*
X681067Y-210405D01*
D02*
G37*
G36*
X666500Y-211192D02*
X665784D01*
X665122Y-211466D01*
X664616Y-211972D01*
X664342Y-212634D01*
Y-213350D01*
X664616Y-214012D01*
X665122Y-214518D01*
X665784Y-214792D01*
X666500D01*
X667161Y-214518D01*
X667423Y-214256D01*
X667992Y-214395D01*
X668159Y-214799D01*
X668665Y-215305D01*
X669327Y-215580D01*
X670043D01*
X670216Y-215508D01*
X670499Y-215932D01*
X670128Y-216303D01*
X669853Y-216965D01*
Y-217681D01*
X670128Y-218342D01*
X670634Y-218849D01*
X671295Y-219123D01*
X672012D01*
X672673Y-218849D01*
X673179Y-218342D01*
X673454Y-217681D01*
Y-216965D01*
X673179Y-216303D01*
X672808Y-215932D01*
X673091Y-215508D01*
X673264Y-215580D01*
X673980D01*
X674642Y-215305D01*
X675148Y-214799D01*
X675422Y-214138D01*
Y-213422D01*
X675148Y-212760D01*
X674642Y-212254D01*
X673980Y-211980D01*
X673264D01*
X672602Y-212254D01*
X672096Y-212760D01*
X671924Y-213175D01*
X671383D01*
X671211Y-212760D01*
X670705Y-212254D01*
X670043Y-211980D01*
X669327D01*
X668665Y-212254D01*
X668404Y-212515D01*
X667835Y-212377D01*
X667668Y-211972D01*
X667161Y-211466D01*
X666500Y-211192D01*
D02*
G37*
G36*
X681067Y-215129D02*
X680351D01*
X679689Y-215403D01*
X679183Y-215910D01*
X678909Y-216571D01*
Y-217287D01*
X679183Y-217949D01*
X679689Y-218455D01*
X680351Y-218729D01*
X681067D01*
X681728Y-218455D01*
X682235Y-217949D01*
X682509Y-217287D01*
Y-216571D01*
X682235Y-215910D01*
X681728Y-215403D01*
X681067Y-215129D01*
D02*
G37*
G36*
X650358Y-229302D02*
X649642D01*
X648980Y-229576D01*
X648474Y-230083D01*
X648458Y-230121D01*
X648232Y-230169D01*
X647899Y-230165D01*
X647454Y-229719D01*
X646792Y-229445D01*
X646076D01*
X645414Y-229719D01*
X644908Y-230225D01*
X644634Y-230887D01*
Y-231603D01*
X644908Y-232265D01*
X645414Y-232771D01*
X646076Y-233045D01*
X646792D01*
X647454Y-232771D01*
X647960Y-232265D01*
X647976Y-232226D01*
X648202Y-232179D01*
X648535Y-232183D01*
X648980Y-232628D01*
X649642Y-232902D01*
X650358D01*
X651020Y-232628D01*
X651526Y-232122D01*
X651800Y-231460D01*
Y-230744D01*
X651526Y-230083D01*
X651020Y-229576D01*
X650358Y-229302D01*
D02*
G37*
G36*
X673586Y-249381D02*
X672870D01*
X672209Y-249655D01*
X671702Y-250162D01*
X671428Y-250823D01*
Y-251539D01*
X671702Y-252201D01*
X672209Y-252707D01*
X672870Y-252981D01*
X673586D01*
X674248Y-252707D01*
X674754Y-252201D01*
X675028Y-251539D01*
Y-250823D01*
X674754Y-250162D01*
X674248Y-249655D01*
X673586Y-249381D01*
D02*
G37*
G36*
X673193Y-255287D02*
X672477D01*
X671815Y-255561D01*
X671309Y-256067D01*
X671035Y-256729D01*
Y-257445D01*
X671309Y-258106D01*
X671815Y-258613D01*
X672477Y-258887D01*
X673193D01*
X673854Y-258613D01*
X674361Y-258106D01*
X674635Y-257445D01*
Y-256729D01*
X674361Y-256067D01*
X673854Y-255561D01*
X673193Y-255287D01*
D02*
G37*
G36*
X673980Y-259617D02*
X673264D01*
X672602Y-259891D01*
X672096Y-260398D01*
X671822Y-261059D01*
Y-261775D01*
X672096Y-262437D01*
X672602Y-262943D01*
X673264Y-263217D01*
X673980D01*
X674642Y-262943D01*
X675148Y-262437D01*
X675422Y-261775D01*
Y-261059D01*
X675148Y-260398D01*
X674642Y-259891D01*
X673980Y-259617D01*
D02*
G37*
G36*
X676736Y-264342D02*
X676020D01*
X675358Y-264616D01*
X674852Y-265122D01*
X674578Y-265784D01*
Y-266500D01*
X674852Y-267161D01*
X675358Y-267668D01*
X676020Y-267942D01*
X676736D01*
X677398Y-267668D01*
X677904Y-267161D01*
X678178Y-266500D01*
Y-265784D01*
X677904Y-265122D01*
X677398Y-264616D01*
X676736Y-264342D01*
D02*
G37*
G36*
X677130Y-269066D02*
X676414D01*
X675752Y-269340D01*
X675246Y-269847D01*
X674972Y-270508D01*
Y-271224D01*
X675246Y-271886D01*
X675752Y-272392D01*
X676414Y-272666D01*
X677130D01*
X677791Y-272392D01*
X678298Y-271886D01*
X678572Y-271224D01*
Y-270508D01*
X678298Y-269847D01*
X677791Y-269340D01*
X677130Y-269066D01*
D02*
G37*
G36*
X671618Y-273003D02*
X670902D01*
X670240Y-273277D01*
X669734Y-273783D01*
X669460Y-274445D01*
Y-275161D01*
X669734Y-275823D01*
X670240Y-276329D01*
X670655Y-276501D01*
Y-277042D01*
X670240Y-277214D01*
X669734Y-277720D01*
X669460Y-278382D01*
Y-279098D01*
X669734Y-279760D01*
X670240Y-280266D01*
X670902Y-280540D01*
X671618D01*
X672280Y-280266D01*
X672786Y-279760D01*
X673060Y-279098D01*
Y-278382D01*
X672786Y-277720D01*
X672280Y-277214D01*
X671864Y-277042D01*
Y-276501D01*
X672280Y-276329D01*
X672786Y-275823D01*
X673060Y-275161D01*
Y-274445D01*
X672786Y-273783D01*
X672280Y-273277D01*
X671618Y-273003D01*
D02*
G37*
G36*
X672012Y-281271D02*
X671295D01*
X670634Y-281545D01*
X670128Y-282051D01*
X669853Y-282713D01*
Y-283429D01*
X670128Y-284090D01*
X670634Y-284597D01*
X671295Y-284871D01*
X672012D01*
X672673Y-284597D01*
X673179Y-284090D01*
X673454Y-283429D01*
Y-282713D01*
X673179Y-282051D01*
X672673Y-281545D01*
X672012Y-281271D01*
D02*
G37*
G36*
X82238Y-285782D02*
X81522D01*
X80860Y-286056D01*
X80354Y-286563D01*
X80080Y-287224D01*
Y-287940D01*
X80354Y-288602D01*
X80860Y-289108D01*
X81522Y-289382D01*
X82238D01*
X82899Y-289108D01*
X83406Y-288602D01*
X83680Y-287940D01*
Y-287224D01*
X83406Y-286563D01*
X82899Y-286056D01*
X82238Y-285782D01*
D02*
G37*
%LPD*%
D12*
X545276Y-205118D02*
X547244Y-203150D01*
X545276Y-208661D02*
Y-205118D01*
Y-208661D02*
X551968Y-215354D01*
Y-264173D02*
Y-215354D01*
X545276Y-270866D02*
X551968Y-264173D01*
X658661Y-271260D02*
Y-224410D01*
X652756Y-218504D02*
X658661Y-224410D01*
X670918Y-310630D02*
X683858D01*
X664966Y-316582D02*
X670918Y-310630D01*
X663044Y-318504D02*
X664966Y-316582D01*
X657087Y-318504D02*
X663044D01*
X653150Y-314567D02*
X657087Y-318504D01*
X648819Y-310236D02*
X653150Y-314567D01*
X638583Y-310236D02*
X648819D01*
X634252Y-314567D02*
X638583Y-310236D01*
X509391Y-350636D02*
X513386Y-346640D01*
Y-342913D01*
X508997Y-338525D02*
X513386Y-342913D01*
X508997Y-338525D02*
Y-335675D01*
X514567Y-330105D01*
Y-301575D01*
X545276Y-270866D01*
D14*
X581496Y-209842D02*
Y-198819D01*
X569291Y-222047D02*
X581496Y-209842D01*
X569291Y-231890D02*
Y-222047D01*
Y-231890D02*
X575984Y-238583D01*
X605118D01*
X608661Y-242126D01*
X631102Y-232677D02*
X637008Y-238583D01*
X575591Y-232677D02*
X631102D01*
X572441Y-229528D02*
X575591Y-232677D01*
X572441Y-229528D02*
Y-227165D01*
X549298Y-191988D02*
X550649D01*
X562992Y-204331D01*
Y-231496D02*
Y-204331D01*
Y-231496D02*
X574016Y-242520D01*
X590551D01*
X78740Y-175197D02*
X86614D01*
X74803Y-179134D02*
X78740Y-175197D01*
D19*
X453937Y-324867D02*
G03*
X453109Y-326866I1999J-1999D01*
G01*
X253871Y-353036D02*
G03*
X252457Y-356451I3415J-3415D01*
G01*
X440496Y-324924D02*
G03*
X440551Y-324852I-368J338D01*
G01*
X452009Y-326866D02*
G03*
X451181Y-324867I-2827J0D01*
G01*
X438623Y-326866D02*
G03*
X437795Y-324867I-2827J0D01*
G01*
X440496Y-324924D02*
G03*
X439907Y-326428I1611J-1499D01*
G01*
X262369Y-378512D02*
G03*
X263119Y-379262I750J0D01*
G01*
X263119Y-380762D02*
G03*
X263119Y-379262I0J750D01*
G01*
X261789Y-380762D02*
G03*
X261789Y-382262I0J-750D01*
G01*
X263077Y-383762D02*
G03*
X263077Y-382262I0J750D01*
G01*
X261970Y-383762D02*
G03*
X261221Y-384512I0J-750D01*
G01*
X262515Y-376738D02*
G03*
X262369Y-377091I354J-353D01*
G01*
X265092Y-374161D02*
G03*
X265557Y-373033I-1135J1128D01*
G01*
X263648Y-375606D02*
G03*
X263617Y-375679I446J-226D01*
G01*
X264312Y-373385D02*
G03*
X264457Y-373033I-355J352D01*
G01*
X262268Y-375487D02*
G03*
X262388Y-375355I-303J397D01*
G01*
X262268Y-375487D02*
G03*
X262139Y-375587I3362J-4466D01*
G01*
D02*
G03*
X260039Y-379958I3491J-4366D01*
G01*
X437962Y-335490D02*
G03*
X438623Y-333893I-1597J1597D01*
G01*
X438901Y-336106D02*
G03*
X439907Y-333679I-2428J2428D01*
G01*
X429620Y-340806D02*
G03*
X437460Y-337559I0J11087D01*
G01*
X257799Y-340806D02*
G03*
X250728Y-343735I0J-10000D01*
G01*
X242558Y-351905D02*
G03*
X239920Y-358273I6368J-6368D01*
G01*
X236673Y-366113D02*
G03*
X239920Y-358273I-7840J7840D01*
G01*
X234833Y-367953D02*
G03*
X231693Y-375524I7581J-7581D01*
G01*
X449862Y-338657D02*
G03*
X453109Y-330817I-7840J7840D01*
G01*
X438720Y-345206D02*
G03*
X446560Y-341959I0J11087D01*
G01*
X267399Y-345206D02*
G03*
X260328Y-348135I0J-10000D01*
G01*
X254657Y-353806D02*
G03*
X253557Y-356462I2656J-2656D01*
G01*
X250978Y-372280D02*
G03*
X253306Y-366660I-5620J5620D01*
G01*
X246410Y-376848D02*
G03*
X246264Y-377201I353J-353D01*
G01*
X246260Y-386706D02*
G03*
X246339Y-386975I500J-0D01*
G01*
X253431Y-363087D02*
G03*
X253306Y-363390I303J-303D01*
G01*
X449080Y-337883D02*
G03*
X452009Y-330812I-7071J7071D01*
G01*
X438715Y-344106D02*
G03*
X445786Y-341177I0J10000D01*
G01*
X267393Y-344106D02*
G03*
X259554Y-347354I0J-11087D01*
G01*
X248559Y-387253D02*
G03*
X248067Y-387647I-3J-500D01*
G01*
X245201Y-388468D02*
G03*
X248067Y-387647I1213J1180D01*
G01*
X242760Y-382451D02*
G03*
X245198Y-388465I8651J6D01*
G01*
X252457Y-362506D02*
G03*
X252206Y-363112I605J-605D01*
G01*
X246511Y-383395D02*
G03*
X246511Y-381894I0J750D01*
G01*
X245513Y-380395D02*
G03*
X246263Y-379645I0J750D01*
G01*
X244849Y-380395D02*
G03*
X244849Y-381894I0J-750D01*
G01*
X244848Y-383395D02*
G03*
X244848Y-384894I0J-750D01*
G01*
X246260Y-385645D02*
G03*
X245511Y-384894I-750J0D01*
G01*
X250197Y-371505D02*
G03*
X252206Y-366655I-4850J4850D01*
G01*
X245247Y-376455D02*
G03*
X242760Y-382451I5995J-6000D01*
G01*
X253431Y-363087D02*
G03*
X253557Y-362785I-303J303D01*
G01*
X267547Y-349419D02*
G03*
X267541Y-349426I8000J-7681D01*
G01*
X436269Y-350033D02*
G03*
X436268Y-350033I-1J-500D01*
G01*
X268693D02*
G03*
X268339Y-350183I3J-500D01*
G01*
X268339Y-350183D02*
G03*
X267969Y-350591I7218J-6921D01*
G01*
X436278Y-350033D02*
G03*
X460782Y-339880I-6J34663D01*
G01*
X267969Y-350591D02*
G03*
X265557Y-357104I7588J-6513D01*
G01*
X268692Y-348933D02*
G03*
X267555Y-349411I3J-1600D01*
G01*
X436273Y-348933D02*
G03*
X460008Y-339100I-6J33573D01*
G01*
X267541Y-349426D02*
G03*
X264457Y-357100I8007J-7675D01*
G01*
X260055Y-387716D02*
G03*
X263814Y-387648I1871J478D01*
G01*
X429615Y-339706D02*
G03*
X435659Y-337673I0J10000D01*
G01*
X264306Y-387253D02*
G03*
X263814Y-387648I-3J-500D01*
G01*
X435659Y-337673D02*
G03*
X436510Y-336930I-5012J6606D01*
G01*
X260039Y-387593D02*
G03*
X260055Y-387716I500J0D01*
G01*
X257793Y-339706D02*
G03*
X249954Y-342954I0J-11087D01*
G01*
X241770Y-351137D02*
G03*
X238820Y-358259I7121J-7121D01*
G01*
X235891Y-365339D02*
G03*
X238820Y-358268I-7071J7071D01*
G01*
X234046Y-367184D02*
G03*
X232307Y-369489I7360J-7360D01*
G01*
X232307Y-369489D02*
G03*
X230464Y-374724I8931J-6086D01*
G01*
X230464D02*
G03*
X230463Y-374763I499J-39D01*
G01*
X230404Y-382730D02*
G03*
X230250Y-383131I1544J-824D01*
G01*
X229180Y-385410D02*
G03*
X229573Y-385160I-41J498D01*
G01*
X231921Y-387253D02*
G03*
X231463Y-387326I0J-1480D01*
G01*
X229180Y-385410D02*
G03*
X231129Y-387687I151J-1844D01*
G01*
X231463Y-387326D02*
G03*
X231131Y-387679I153J-476D01*
G01*
X230404Y-382730D02*
G03*
X230463Y-382494I-441J236D01*
G01*
X229789Y-384818D02*
G03*
X229864Y-384653I-410J286D01*
G01*
X229789Y-384818D02*
G03*
X229573Y-385160I3743J-2610D01*
G01*
X233430Y-382804D02*
G03*
X233430Y-381304I0J750D01*
G01*
X231693Y-377554D02*
G03*
X232443Y-378304I750J-0D01*
G01*
X233066Y-379804D02*
G03*
X233066Y-378304I0J750D01*
G01*
X232213Y-379804D02*
G03*
X232213Y-381304I0J-750D01*
G01*
X231948Y-382804D02*
G03*
X231221Y-383370I0J-750D01*
G01*
X230556Y-385679D02*
G03*
X230699Y-385429I-6928J4128D01*
G01*
X229331Y-387253D02*
G03*
X230556Y-385679I-5703J5703D01*
G01*
X429124Y-321299D02*
G03*
X427953Y-324124I2828J-2828D01*
G01*
X253399Y-338606D02*
G03*
X246328Y-341535I0J-10000D01*
G01*
X253393Y-337506D02*
G03*
X245554Y-340754I0J-11087D01*
G01*
X230857Y-357006D02*
G03*
X227906Y-364131I7126J-7126D01*
G01*
X217253Y-388562D02*
G03*
X217903Y-386760I-1592J1592D01*
G01*
X436221Y-306757D02*
G03*
X435393Y-308755I1999J-1999D01*
G01*
X432145Y-318278D02*
G03*
X435393Y-310438I-7840J7840D01*
G01*
X425240Y-335079D02*
G03*
X427953Y-328529I-6549J6549D01*
G01*
X417117Y-338606D02*
G03*
X424962Y-335357I0J11093D01*
G01*
X214137Y-387647D02*
G03*
X213646Y-387253I-489J-106D01*
G01*
X214137Y-387647D02*
G03*
X217253Y-388562I1808J394D01*
G01*
X434293Y-308755D02*
G03*
X433465Y-306757I-2827J0D01*
G01*
X431364Y-317504D02*
G03*
X434293Y-310433I-7071J7071D01*
G01*
X428344Y-320523D02*
G03*
X426853Y-324125I3601J-3601D01*
G01*
X417114Y-337506D02*
G03*
X424186Y-334577I0J10000D01*
G01*
X230077Y-356230D02*
G03*
X226829Y-364073I7842J-7842D01*
G01*
X424457Y-334306D02*
G03*
X426853Y-328522I-5785J5785D01*
G01*
X223000Y-379138D02*
G03*
X224061Y-379138I530J530D01*
G01*
X223000Y-379138D02*
G03*
X221939Y-379138I-530J-530D01*
G01*
D02*
G03*
X221939Y-380199I530J-530D01*
G01*
X221939Y-381259D02*
G03*
X221939Y-380199I-530J530D01*
G01*
X220879Y-381259D02*
G03*
X221939Y-381259I530J530D01*
G01*
X220632Y-381013D02*
G03*
X219571Y-381013I-530J-530D01*
G01*
D02*
G03*
X219571Y-382073I530J-530D01*
G01*
X219818Y-383381D02*
G03*
X219818Y-382320I-530J530D01*
G01*
X218428Y-383051D02*
G03*
X217367Y-383051I-530J-530D01*
G01*
X218757Y-383381D02*
G03*
X219818Y-383381I530J530D01*
G01*
X217367Y-383051D02*
G03*
X217367Y-384112I530J-530D01*
G01*
X217696Y-385502D02*
G03*
X217696Y-384441I-530J530D01*
G01*
X261221Y-386262D02*
G03*
X261367Y-386616I500J0D01*
G01*
X450221Y-314836D02*
G03*
X457292Y-317765I7071J7071D01*
G01*
X465157Y-324873D02*
G03*
X462788Y-319156I-8086J0D01*
G01*
X462773Y-319140D02*
G03*
X459454Y-317765I-3320J-3320D01*
G01*
X448032Y-306757D02*
G03*
X447204Y-308755I1999J-1999D01*
G01*
X447203Y-310285D02*
G03*
X448288Y-312904I3704J0D01*
G01*
X461907Y-338755D02*
G03*
X465157Y-330911I-7844J7844D01*
G01*
X446103Y-310291D02*
G03*
X447507Y-313678I4791J0D01*
G01*
X449445Y-315617D02*
G03*
X457288Y-318865I7842J7842D01*
G01*
X446103Y-308755D02*
G03*
X445276Y-306757I-2827J0D01*
G01*
X464057Y-324890D02*
G03*
X461999Y-319922I-7026J0D01*
G01*
D02*
G03*
X459449Y-318865I-2550J-2550D01*
G01*
X461128Y-337980D02*
G03*
X464057Y-330908I-7071J7071D01*
G01*
X452009Y-330812D02*
Y-326866D01*
X246264Y-377201D02*
X246264Y-377201D01*
X438623Y-333893D02*
Y-326866D01*
X437795Y-324867D02*
Y-324852D01*
X439907Y-326428D02*
X439907Y-333679D01*
X453109Y-330817D02*
Y-326866D01*
X253871Y-353036D02*
X259554Y-347354D01*
X451181Y-324867D02*
Y-324852D01*
X440551Y-324852D02*
Y-324852D01*
X453937Y-324867D02*
Y-324852D01*
X262369Y-378512D02*
Y-377362D01*
X263119Y-379262D02*
X263119D01*
X261789Y-380762D02*
X263119D01*
X261789Y-382262D02*
X263077D01*
X261970Y-383762D02*
X263077D01*
X261221Y-386013D02*
Y-384512D01*
Y-386013D02*
X261221Y-386262D01*
X262515Y-376738D02*
X265092Y-374161D01*
X265557Y-373033D02*
Y-357104D01*
X264457Y-373033D02*
Y-357100D01*
X262369Y-377362D02*
Y-377091D01*
X263617Y-375679D02*
X263617D01*
X263648Y-375606D02*
X263648Y-375604D01*
X262468Y-375229D02*
X264312Y-373385D01*
X262388Y-375355D02*
X262468Y-375229D01*
X260039Y-387593D02*
Y-379958D01*
X227906Y-376757D02*
Y-364916D01*
X226829Y-376370D02*
Y-364916D01*
X226441Y-376757D02*
X226829Y-376370D01*
X227906Y-364916D02*
Y-364131D01*
X226829Y-364916D02*
Y-364073D01*
X225816Y-377383D02*
X226441Y-376757D01*
X437460Y-337559D02*
Y-337548D01*
X438901Y-336106D01*
X257799Y-340806D02*
X429620D01*
X242558Y-351905D02*
X250728Y-343735D01*
X234833Y-367953D02*
X236673Y-366113D01*
X234833Y-367953D02*
X234833Y-367953D01*
X231693Y-376230D02*
X231693Y-375524D01*
X446560Y-341959D02*
X449862Y-338657D01*
X267399Y-345206D02*
X438720D01*
X254657Y-353806D02*
X260328Y-348135D01*
X253557Y-362785D02*
Y-356462D01*
X246410Y-376848D02*
X250978Y-372280D01*
X246339Y-386975D02*
X246339Y-386975D01*
X246260Y-386706D02*
X246260D01*
X253306Y-366660D02*
Y-363390D01*
X445786Y-341177D02*
X449080Y-337883D01*
X267393Y-344106D02*
X438715D01*
X252457Y-362506D02*
Y-356451D01*
X248559Y-387253D02*
X249410D01*
X245198Y-388465D02*
X245201Y-388468D01*
X252206Y-366655D02*
Y-363112D01*
X246264Y-377451D02*
X246264Y-377201D01*
X246263Y-379645D02*
X246264Y-377451D01*
X246263Y-379645D02*
X246263D01*
X244849Y-381894D02*
X246511D01*
X246260Y-386020D02*
X246260Y-385645D01*
X244848Y-383395D02*
X246511D01*
X244849Y-380395D02*
X245513D01*
X246260Y-385645D02*
X246260D01*
X244848Y-384894D02*
X245511D01*
X246260Y-386270D02*
X246260Y-386020D01*
X246260Y-386706D02*
X246260Y-386270D01*
X245247Y-376455D02*
X250197Y-371505D01*
X436269Y-350033D02*
X436278D01*
X268339Y-350183D02*
X268339Y-350183D01*
X268693Y-350033D02*
X436268D01*
X268692Y-348933D02*
X436273Y-348933D01*
X267547Y-349419D02*
X267555Y-349411D01*
X263814Y-387648D02*
X263814Y-387648D01*
X257793Y-339706D02*
X429615D01*
X436510Y-336930D02*
X436521D01*
X241770Y-351137D02*
X249954Y-342954D01*
X238820Y-358268D02*
Y-358259D01*
X234046Y-367184D02*
X235891Y-365339D01*
X232307Y-369489D02*
Y-369489D01*
X230464Y-374724D02*
X230464D01*
X230463Y-382494D02*
X230463Y-374763D01*
X230249Y-383132D02*
X230250Y-383131D01*
X229864Y-384653D02*
X230249Y-383132D01*
X231921Y-387253D02*
X232480D01*
X229180Y-385410D02*
X229180Y-385410D01*
X231463Y-387326D02*
Y-387326D01*
X231129Y-387687D02*
X231131Y-387679D01*
X436521Y-336930D02*
X437962Y-335490D01*
X232443Y-378304D02*
X233066D01*
X232213Y-381304D02*
X233430D01*
X232213Y-379804D02*
X233066D01*
X231693Y-376230D02*
Y-376230D01*
X231693Y-376480D02*
X231693Y-376230D01*
X231693Y-377554D02*
X231693Y-376480D01*
X231948Y-382804D02*
X233430D01*
X231221Y-383370D02*
X231221D01*
X230699Y-385429D02*
X231221Y-383370D01*
X253399Y-338606D02*
X417117D01*
X429124Y-321299D02*
X429124Y-321299D01*
X253393Y-337506D02*
X417114D01*
X429124Y-321299D02*
X432145Y-318278D01*
X427953Y-328529D02*
Y-324124D01*
X230857Y-357006D02*
X246328Y-341535D01*
X230077Y-356230D02*
X245554Y-340754D01*
X217903Y-386760D02*
X227906Y-376757D01*
X436221Y-306757D02*
Y-306742D01*
X435393Y-310438D02*
Y-308755D01*
X424962Y-335357D02*
X425240Y-335079D01*
X213646Y-387253D02*
X213646D01*
X212795D02*
X213646D01*
X434293Y-310433D02*
Y-308755D01*
X433465Y-306757D02*
Y-306742D01*
X428344Y-320523D02*
X431364Y-317504D01*
X426853Y-328522D02*
Y-324125D01*
X424186Y-334577D02*
X424457Y-334306D01*
X224061Y-379138D02*
X225816Y-377383D01*
X223000Y-379138D02*
X223000Y-379138D01*
X223000Y-379138D02*
X223000Y-379138D01*
X221939Y-380199D02*
X221939Y-380199D01*
X220632Y-381013D02*
X220879Y-381259D01*
X219571Y-382073D02*
X219818Y-382320D01*
X218428Y-383051D02*
X218757Y-383381D01*
X217367Y-384112D02*
X217696Y-384441D01*
X217520Y-385679D02*
X217696Y-385502D01*
X215945Y-387253D02*
X217520Y-385679D01*
X457292Y-317765D02*
X459454D01*
X448288Y-312904D02*
X450221Y-314836D01*
X462773Y-319140D02*
X462788Y-319156D01*
X448032Y-306757D02*
Y-306742D01*
X447203Y-310285D02*
Y-308755D01*
X465157Y-330911D02*
Y-324873D01*
X460782Y-339880D02*
X461907Y-338755D01*
X264306Y-387253D02*
X265158D01*
X446103Y-310291D02*
Y-308755D01*
X457288Y-318865D02*
X459449D01*
X445276Y-306757D02*
Y-306742D01*
X464057Y-330908D02*
Y-324890D01*
X459449Y-318865D02*
Y-318865D01*
X261367Y-386616D02*
X262006Y-387255D01*
X447507Y-313678D02*
X449445Y-315617D01*
X460008Y-339100D02*
X461128Y-337980D01*
D24*
X668103Y-68217D02*
G03*
X668110Y-68042I-2058J175D01*
G01*
X668910Y-63762D02*
G03*
X668110Y-64561I0J-800D01*
G01*
X669062Y-63762D02*
G03*
X669062Y-62462I0J650D01*
G01*
X668760Y-61162D02*
G03*
X668760Y-62462I0J-650D01*
G01*
X669062Y-61162D02*
G03*
X669062Y-59861I0J650D01*
G01*
X668110Y-59061D02*
G03*
X668910Y-59861I800J0D01*
G01*
X665473Y-76127D02*
G03*
X664673Y-76927I0J-800D01*
G01*
X665473Y-76127D02*
G03*
X665473Y-74827I0J650D01*
G01*
X664673Y-74027D02*
G03*
X665473Y-74827I800J0D01*
G01*
X667505Y-69503D02*
G03*
X668103Y-68217I-1461J1461D01*
G01*
X670538Y-74409D02*
G03*
X670200Y-75225I816J-816D01*
G01*
X669323Y-82909D02*
G03*
X669324Y-82908I-915J924D01*
G01*
X668110Y-83583D02*
G03*
X669032Y-83200I0J1300D01*
G01*
X663373Y-82284D02*
G03*
X664673Y-83583I1300J0D01*
G01*
X663694Y-71475D02*
G03*
X663373Y-72250I776J-776D01*
G01*
X667188Y-57745D02*
G03*
X666810Y-58661I922J-917D01*
G01*
X666429Y-68740D02*
G03*
X666810Y-67758I-7440J3452D01*
G01*
X673228Y-52553D02*
G03*
X671778Y-53155I0J-2047D01*
G01*
X674411Y-52553D02*
G03*
X676772Y-51575I0J3339D01*
G01*
X668898Y-75519D02*
G03*
X668438Y-74409I-1569J0D01*
G01*
X668408Y-81985D02*
G03*
X669500Y-80455I-4033J4033D01*
G01*
X665354Y-71653D02*
G03*
X664673Y-72560I2851J-2851D01*
G01*
X673228Y-53853D02*
G03*
X672700Y-54072I0J-747D01*
G01*
X676772Y-54331D02*
G03*
X675779Y-53646I-2361J-2361D01*
G01*
X674411Y-53853D02*
G03*
X675779Y-53646I0J4639D01*
G01*
X670669Y-81025D02*
G03*
X670671Y-81020I-6293J3073D01*
G01*
X669324Y-82908D02*
G03*
X670669Y-81025I-4948J4955D01*
G01*
X670671Y-81020D02*
G03*
X670788Y-80274I-1171J565D01*
G01*
X322220Y-153543D02*
G03*
X319291Y-160614I7071J-7071D01*
G01*
X334236Y-145669D02*
G03*
X327165Y-148598I0J-10000D01*
G01*
X380844Y-145669D02*
G03*
X384646Y-144095I0J5377D01*
G01*
X389758Y-141977D02*
G03*
X384646Y-144095I0J-7230D01*
G01*
X169783Y-298425D02*
G03*
X154158Y-304897I0J-22098D01*
G01*
X298661Y-225590D02*
G03*
X310236Y-214016I0J11575D01*
G01*
X311417Y-134646D02*
G03*
X310236Y-135827I0J-1181D01*
G01*
X288976Y-131102D02*
G03*
X279388Y-134308I0J-15943D01*
G01*
D02*
G03*
X273741Y-146927I11275J-12619D01*
G01*
X311024Y-131102D02*
G03*
X312205Y-129921I0J1181D01*
G01*
X273741Y-222047D02*
G03*
X273741Y-222116I11627J-0D01*
G01*
D02*
G03*
X283872Y-232178I10130J69D01*
G01*
X290709Y-128659D02*
G03*
X272441Y-146927I0J-18268D01*
G01*
Y-222047D02*
G03*
X283872Y-233478I11431J0D01*
G01*
X395669Y-164608D02*
G03*
X398598Y-171678I10000J0D01*
G01*
X398609Y-153359D02*
G03*
X398608Y-153360I3359J-3361D01*
G01*
X401968Y-151969D02*
G03*
X398609Y-153359I0J-4752D01*
G01*
X401968Y-151969D02*
G03*
X403150Y-149117I-2851J2851D01*
G01*
X316362Y-237575D02*
G03*
X319291Y-230504I-7071J7071D01*
G01*
X306079Y-247859D02*
G03*
X303150Y-254929I7071J-7071D01*
G01*
Y-268692D02*
G03*
X306079Y-275764I10000J0D01*
G01*
X358566Y-278740D02*
G03*
X361417Y-277559I0J4033D01*
G01*
X370079Y-272047D02*
G03*
X364702Y-274274I0J-7604D01*
G01*
X387984Y-272047D02*
G03*
X395055Y-269118I0J10000D01*
G01*
X420284Y-248031D02*
G03*
X413213Y-250960I0J-10000D01*
G01*
X518110Y-251833D02*
G03*
X516535Y-248031I-5377J0D01*
G01*
X297894Y-228740D02*
G03*
X311811Y-214823I0J13917D01*
G01*
X317717Y-117323D02*
G03*
X314380Y-113986I-3337J0D01*
G01*
X315748Y-136614D02*
G03*
X317717Y-134646I0J1969D01*
G01*
X314173Y-136614D02*
G03*
X311811Y-138976I0J-2362D01*
G01*
X311417Y-134646D02*
G03*
X314961Y-131102I0J3543D01*
G01*
X312205Y-127017D02*
G03*
X309055Y-123868I-3150J0D01*
G01*
X262425Y-244315D02*
G03*
X269496Y-247244I7071J7071D01*
G01*
X288189Y-247638D02*
G03*
X287239Y-247244I-950J-950D01*
G01*
X192126Y-169874D02*
G03*
X195055Y-176945I10000J0D01*
G01*
X193898Y-115009D02*
G03*
X192126Y-116781I0J-1772D01*
G01*
X262638Y-242166D02*
G03*
X269710Y-245095I7071J7071D01*
G01*
X193898Y-169283D02*
G03*
X196827Y-176354I10000J0D01*
G01*
X668110Y-68042D02*
Y-64561D01*
X668910Y-63762D02*
X669062D01*
X668760Y-62462D02*
X669062D01*
X668760Y-61162D02*
X669062D01*
X668910Y-59861D02*
X669062D01*
X668110Y-59061D02*
Y-58661D01*
X664673Y-81675D02*
Y-76927D01*
X665473Y-76127D02*
X665473D01*
X665473Y-74827D02*
X665473D01*
X664673Y-74027D02*
Y-73627D01*
Y-82284D02*
Y-81675D01*
Y-73627D02*
Y-72560D01*
X665354Y-71653D02*
X667505Y-69503D01*
X670200Y-75916D02*
Y-75225D01*
X669032Y-83200D02*
X669323Y-82909D01*
X664673Y-83583D02*
X668110D01*
X663373Y-82284D02*
Y-72250D01*
X666810Y-67758D02*
Y-58661D01*
X663694Y-71475D02*
X666429Y-68740D01*
X667188Y-57745D02*
X671778Y-53155D01*
X673228Y-52553D02*
X674411D01*
X668898Y-75984D02*
Y-75519D01*
Y-75984D02*
X669500Y-80455D01*
Y-80455D02*
Y-80455D01*
X668110Y-58661D02*
X672700Y-54072D01*
X673228Y-53853D02*
X674411D01*
X670200Y-75916D02*
X670788Y-80274D01*
X668110Y-82284D02*
X668408Y-81985D01*
X664673Y-82284D02*
X668110D01*
X645669Y-54724D02*
X660868D01*
X692762Y-47638D02*
X696577Y-51453D01*
X660868Y-54724D02*
X667954Y-47638D01*
X692762D01*
X178593Y-347043D02*
X198392Y-366842D01*
X141981Y-347043D02*
X178593D01*
X142520Y-342913D02*
X182283D01*
X202756Y-363386D01*
Y-368110D02*
Y-363386D01*
X200343Y-370523D02*
X202756Y-368110D01*
X196701Y-370523D02*
X200343D01*
X596457Y-112598D02*
X637867Y-71188D01*
X584252Y-112598D02*
X596457D01*
X566145Y-130705D02*
X584252Y-112598D01*
X324410Y-118898D02*
X335827Y-130315D01*
X385827D02*
X395720Y-120422D01*
X335827Y-130315D02*
X385827D01*
X322441Y-121653D02*
X332677Y-131890D01*
X388189D02*
X399632Y-120447D01*
X332677Y-131890D02*
X388189D01*
X392520Y-133465D02*
X399059Y-126926D01*
X320853Y-125971D02*
X328346Y-133465D01*
X392520D01*
X322441Y-108268D02*
X324410Y-110236D01*
X395720Y-117272D02*
X400000Y-112992D01*
X324410Y-118898D02*
Y-110236D01*
X395720Y-120422D02*
Y-117272D01*
X320472Y-110236D02*
X322441Y-112205D01*
X399632Y-117691D02*
X403289Y-114033D01*
X322441Y-121653D02*
Y-112205D01*
X399632Y-120447D02*
Y-117691D01*
X318504Y-112205D02*
X320853Y-114554D01*
X399059Y-123382D02*
X406398Y-116043D01*
X320853Y-125971D02*
Y-114554D01*
X399059Y-126926D02*
Y-123382D01*
X322220Y-153543D02*
X327165Y-148598D01*
X319291Y-230504D02*
Y-160614D01*
X334236Y-145669D02*
X380844D01*
X399851Y-141977D02*
X403150Y-145276D01*
X389758Y-141977D02*
X399851D01*
X442520Y-111811D02*
X443307Y-111024D01*
X403241Y-111811D02*
X442520D01*
X402719Y-112334D02*
X403241Y-111811D01*
X432677Y-132677D02*
X436614Y-136614D01*
X413782Y-132677D02*
X432677D01*
X409900Y-136559D02*
X413782Y-132677D01*
X587008Y-264567D02*
X588189Y-263386D01*
X555905Y-264567D02*
X587008D01*
X545276Y-275197D02*
X555905Y-264567D01*
X241250Y-126247D02*
X241750Y-125747D01*
X254376D01*
X257874Y-123031D02*
Y-121653D01*
X254376Y-125747D02*
X255159D01*
X257874Y-123031D01*
Y-121653D02*
X271260Y-108268D01*
X322441D01*
X400000Y-112992D02*
Y-109449D01*
X424803D01*
X430709Y-103543D01*
X435827D01*
X447915Y-201740D02*
X462205Y-187450D01*
X461319Y-143750D02*
X462205Y-144635D01*
Y-187450D02*
Y-144635D01*
X450917Y-219340D02*
X622177Y-48080D01*
X625000D01*
X414240Y-219340D02*
X450917D01*
X151181Y-120079D02*
X151496D01*
X136614Y-134646D02*
X151181Y-120079D01*
X92237Y-134646D02*
X136614D01*
X87254Y-139629D02*
X92237Y-134646D01*
X144961Y-136614D02*
X161496Y-120079D01*
X98032Y-136614D02*
X144961D01*
X94376Y-140270D02*
X98032Y-136614D01*
X89567Y-140270D02*
X94376D01*
X89567Y-143504D02*
Y-140270D01*
Y-143504D02*
X92913Y-146850D01*
X122047D01*
X130315Y-138583D01*
X172835D01*
X175984Y-135433D01*
Y-114961D01*
X183858Y-107087D01*
X192520D01*
X223622Y-138189D01*
X260630D01*
X87254Y-146309D02*
Y-139629D01*
Y-146309D02*
X90551Y-149606D01*
X122835D01*
X131102Y-141339D01*
X177953D01*
X188976Y-130315D01*
Y-111024D01*
X192520D01*
X223228Y-141732D01*
X261417D01*
X260630Y-138189D02*
Y-122441D01*
X272835Y-110236D01*
X320472D01*
X403423Y-114033D02*
X403677Y-113779D01*
X403289Y-114033D02*
X403423D01*
X403677Y-113779D02*
X461306D01*
X463551Y-116025D01*
X261417Y-141732D02*
X262992Y-140157D01*
Y-123622D01*
X274410Y-112205D01*
X318504D01*
X406398Y-116043D02*
X456742D01*
X565354Y-96063D02*
X567323Y-94095D01*
X472047Y-96063D02*
X565354D01*
X466142Y-101969D02*
X472047Y-96063D01*
X466142Y-188976D02*
Y-101969D01*
X449213Y-205906D02*
X466142Y-188976D01*
X381890Y-205906D02*
X449213D01*
X381890Y-226378D02*
Y-205906D01*
X355512Y-252756D02*
X381890Y-226378D01*
X351969Y-252756D02*
X355512D01*
X346063Y-258661D02*
X351969Y-252756D01*
X336221Y-258661D02*
X346063D01*
X325984Y-268898D02*
X336221Y-258661D01*
X325984Y-272441D02*
Y-268898D01*
X642520Y-57874D02*
X645669Y-54724D01*
X635039Y-57874D02*
X642520D01*
X634252Y-58661D02*
X635039Y-57874D01*
X634252Y-63386D02*
Y-58661D01*
X614567Y-83071D02*
X634252Y-63386D01*
X614567Y-87402D02*
Y-83071D01*
X612992Y-88976D02*
X614567Y-87402D01*
X612598Y-88976D02*
X612992D01*
X611417Y-90158D02*
X612598Y-88976D01*
X607480Y-90158D02*
X611417D01*
X606693Y-90945D02*
X607480Y-90158D01*
X606693Y-93102D02*
Y-90945D01*
X601745Y-98051D02*
X606693Y-93102D01*
X599279Y-82981D02*
X607571D01*
X615748Y-74803D01*
Y-67716D01*
X637795Y-45669D01*
X672441D01*
X675591Y-42520D01*
X595276Y-109055D02*
X636016Y-68314D01*
X644568Y-59762D02*
X647616Y-56714D01*
X636016Y-68314D02*
Y-62015D01*
X638269Y-59762D01*
X644568D01*
X578346Y-109055D02*
X595276D01*
X647616Y-56714D02*
X658114D01*
X595669Y-111024D02*
X637402Y-69291D01*
X581102Y-111024D02*
X595669D01*
X637402Y-69291D02*
X649213D01*
X588189Y-107087D02*
X620159Y-75117D01*
X623511Y-65859D02*
Y-62552D01*
X620159Y-75117D02*
Y-69211D01*
X623511Y-65859D01*
X576378Y-107087D02*
X588189D01*
X542520Y-137795D02*
X573228Y-107087D01*
X538189Y-164173D02*
X542520Y-159843D01*
Y-137795D01*
X539764Y-169291D02*
X550000Y-159055D01*
Y-133465D02*
X576378Y-107087D01*
X550000Y-159055D02*
Y-133465D01*
X481890Y-100000D02*
X515117D01*
X450000Y-209842D02*
X515231Y-144612D01*
X515117Y-100000D02*
X515231Y-100114D01*
Y-144612D02*
Y-100114D01*
X360204Y-252984D02*
X365913D01*
X409055Y-209842D01*
X450000D01*
X475984Y-105905D02*
X481890Y-100000D01*
X473228Y-105905D02*
X475984D01*
X503543Y-298425D02*
X518110Y-283858D01*
X169783Y-298425D02*
X503543D01*
X310236Y-214016D02*
Y-135827D01*
X288976Y-131102D02*
X311024D01*
X273741Y-146927D02*
X273741D01*
Y-146927D01*
X283872Y-232178D02*
X286953D01*
X287513Y-231778D02*
X288189Y-231102D01*
X286953Y-232178D02*
X287353Y-231778D01*
X287513D01*
X273741Y-222047D02*
Y-146927D01*
X272441Y-222047D02*
Y-146927D01*
X518337Y-160463D02*
Y-159634D01*
X515702Y-164521D02*
Y-162803D01*
X498693Y-188351D02*
X498855Y-188189D01*
X535039D01*
X498819Y-183858D02*
X499213Y-183465D01*
X536614D01*
X499111Y-179528D02*
X499111Y-179528D01*
X536614D01*
X518337Y-160463D02*
X522047Y-164173D01*
X538189D01*
X573228Y-107087D02*
Y-105118D01*
X623228Y-55118D01*
X515702Y-164521D02*
X520472Y-169291D01*
X539764D01*
X536614Y-179528D02*
X551575Y-164567D01*
Y-135827D01*
X578346Y-109055D01*
X536614Y-183465D02*
X555118Y-164961D01*
Y-137008D01*
X581102Y-111024D01*
X649213Y-69291D02*
X654978Y-63525D01*
X657445D01*
X535039Y-188189D02*
X557874Y-165354D01*
Y-138976D01*
X565113Y-131701D02*
X566109Y-130705D01*
X566145D01*
X565113Y-131737D02*
Y-131701D01*
X557874Y-138976D02*
X565113Y-131737D01*
X637867Y-71188D02*
X658053D01*
X427165Y-178347D02*
Y-175246D01*
X411417Y-194095D02*
X427165Y-178347D01*
X375000Y-194095D02*
X411417D01*
X375000Y-230315D02*
Y-194095D01*
X398598Y-171678D02*
X402264Y-175344D01*
X404823D01*
X395669Y-164608D02*
Y-156299D01*
X398608Y-153360D02*
X398609Y-153359D01*
X395669Y-156299D02*
X398608Y-153360D01*
X306079Y-247859D02*
X316362Y-237575D01*
X303150Y-268692D02*
Y-254929D01*
X309055Y-278740D02*
X358566D01*
X306079Y-275764D02*
X309055Y-278740D01*
X403150Y-149117D02*
Y-145276D01*
X361417Y-277559D02*
X364702Y-274274D01*
X370079Y-272047D02*
X387984D01*
X395055Y-269118D02*
X413213Y-250960D01*
X420284Y-248031D02*
X516535D01*
X518110Y-283858D02*
Y-251833D01*
X142520Y-316535D02*
X154158Y-304897D01*
X498376Y-279134D02*
X512402Y-265108D01*
X498376Y-275984D02*
X512402Y-261958D01*
X357135Y-288189D02*
X366191Y-279134D01*
X356742Y-286221D02*
X366978Y-275984D01*
X357923Y-292126D02*
X363188Y-286861D01*
X496259D01*
X512657Y-270462D01*
X366191Y-279134D02*
X498376D01*
X357529Y-290158D02*
X366024Y-281662D01*
X498946D02*
X512543Y-268065D01*
X366978Y-275984D02*
X498376D01*
X366024Y-281662D02*
X498946D01*
X105865Y-237409D02*
X158613Y-290158D01*
X357529D01*
X158219Y-292126D02*
X357923D01*
X159006Y-288189D02*
X357135D01*
X108465Y-235809D02*
X158876Y-286221D01*
X104528Y-238435D02*
X158219Y-292126D01*
X107165Y-236347D02*
X159006Y-288189D01*
X158876Y-286221D02*
X356742D01*
X326304Y-250984D02*
X354331D01*
X320095Y-244775D02*
X326304Y-250984D01*
X314658Y-244775D02*
X320095D01*
X434646Y-162598D02*
Y-156840D01*
Y-162598D02*
X440551Y-168504D01*
Y-177953D02*
Y-168504D01*
X418898Y-144143D02*
X421949D01*
X434646Y-156840D01*
X439370Y-179134D02*
X440551Y-177953D01*
X434282Y-179134D02*
X439370D01*
X416835Y-196581D02*
X434282Y-179134D01*
X416106Y-148783D02*
Y-144180D01*
Y-148783D02*
X423622Y-156299D01*
Y-167205D02*
Y-156299D01*
Y-167205D02*
X429001Y-172584D01*
Y-179660D02*
Y-172584D01*
X411811Y-196850D02*
X429001Y-179660D01*
X311811Y-214823D02*
Y-138976D01*
X288189Y-228740D02*
X297894D01*
X309016Y-113986D02*
X314380D01*
X317717Y-134646D02*
Y-117323D01*
X314173Y-136614D02*
X315748D01*
X288583Y-225590D02*
X298661D01*
X314961Y-131102D02*
Y-118947D01*
X312205Y-129921D02*
Y-127017D01*
X290709Y-128659D02*
X309016D01*
X283872Y-233478D02*
X288057D01*
X195055Y-176945D02*
X262425Y-244315D01*
X269496Y-247244D02*
X287239D01*
X192126Y-169874D02*
Y-116781D01*
X269710Y-245095D02*
X288057D01*
X196827Y-176354D02*
X262638Y-242166D01*
X193898Y-169283D02*
Y-119931D01*
X104528Y-238435D02*
Y-176972D01*
X26495Y-98940D02*
X104528Y-176972D01*
X364994Y-268586D02*
X414240Y-219340D01*
X360236Y-268586D02*
X364994D01*
X26495Y-98940D02*
Y-8991D01*
X345669Y-203150D02*
X361417D01*
X337691Y-195171D02*
X345669Y-203150D01*
X326966Y-195171D02*
X337691D01*
X326969Y-197573D02*
X337731D01*
X347244Y-207087D02*
X361811D01*
X337731Y-197573D02*
X347244Y-207087D01*
X358661Y-194488D02*
X366535Y-202362D01*
X372047Y-163238D02*
X390202Y-145083D01*
X398568D01*
X372047Y-200756D02*
Y-163238D01*
X451048Y-217372D02*
X630772Y-37647D01*
X658465D01*
X39370Y-108138D02*
Y-9843D01*
Y-108138D02*
X107165Y-175932D01*
X39370Y-9843D02*
X40354Y-8858D01*
X377921Y-203740D02*
X448671D01*
X464328Y-188083D01*
X354331Y-250984D02*
X375000Y-230315D01*
X372016Y-200787D02*
X372047Y-200756D01*
X107165Y-236347D02*
Y-175932D01*
X105865Y-237409D02*
Y-176471D01*
X108465Y-235809D02*
Y-175394D01*
X379921Y-201740D02*
X447915D01*
X33465Y-104071D02*
X105865Y-176471D01*
X102394Y-211449D02*
X102528Y-211583D01*
X47244Y-114173D02*
X108465Y-175394D01*
X102394Y-211449D02*
Y-185088D01*
X95472Y-208661D02*
X101378Y-214567D01*
X95472Y-208661D02*
Y-185039D01*
X90551Y-180118D02*
X95472Y-185039D01*
X91660Y-219488D02*
X97125D01*
X82677Y-228471D02*
X91660Y-219488D01*
X82677Y-232283D02*
Y-228471D01*
X91535Y-216535D02*
X99410D01*
X86614Y-221457D02*
X91535Y-216535D01*
X86562Y-169257D02*
X102394Y-185088D01*
X80709Y-180118D02*
X90551D01*
X360236Y-262186D02*
X365619D01*
X365556Y-266186D02*
X414370Y-217372D01*
X360236Y-266186D02*
X365556D01*
X47244Y-114173D02*
Y-8858D01*
X33465Y-104071D02*
Y-8858D01*
X413386Y-214419D02*
X450323D01*
X365619Y-262186D02*
X413386Y-214419D01*
X414370Y-217372D02*
X451048D01*
X618110Y-46632D02*
Y-28789D01*
X450323Y-214419D02*
X618110Y-46632D01*
X464328Y-188083D02*
Y-146397D01*
X618110Y-28789D02*
X625000Y-21899D01*
D240*
X161496Y-120079D02*
D03*
X151496D02*
D03*
D241*
X142520Y-316535D02*
D03*
D03*
D250*
X670538Y-74409D02*
D03*
X668438D02*
D03*
X676772Y-54331D02*
D03*
Y-51575D02*
D03*
X141981Y-347043D02*
D03*
X142520Y-342913D02*
D03*
X198392Y-366842D02*
D03*
X196701Y-370523D02*
D03*
X679921Y-160236D02*
D03*
X684646Y-161811D02*
D03*
X689370Y-161417D02*
D03*
X689764Y-164567D02*
D03*
Y-168110D02*
D03*
X625000Y-48080D02*
D03*
X381496Y-127165D02*
D03*
X378740Y-123622D02*
D03*
X435827Y-103543D02*
D03*
X402719Y-112334D02*
D03*
X409900Y-136559D02*
D03*
X436614Y-136614D02*
D03*
X443307Y-111024D02*
D03*
X664966Y-316582D02*
D03*
X254376Y-125747D02*
D03*
X241250Y-126247D02*
D03*
X599279Y-82981D02*
D03*
X601745Y-98051D02*
D03*
X567323Y-94095D02*
D03*
X696577Y-51453D02*
D03*
X675591Y-42520D02*
D03*
X570472Y-137795D02*
D03*
X579921Y-133465D02*
D03*
X574409D02*
D03*
X570866D02*
D03*
X572047Y-129921D02*
D03*
X576378D02*
D03*
X580315D02*
D03*
X572441Y-227165D02*
D03*
X652756Y-218504D02*
D03*
X598425Y-198819D02*
D03*
X595276D02*
D03*
X592126D02*
D03*
X589764D02*
D03*
X587008D02*
D03*
X549298Y-191988D02*
D03*
X683858Y-310630D02*
D03*
X651575Y-275197D02*
D03*
X648819Y-278740D02*
D03*
X652362Y-279528D02*
D03*
X657087D02*
D03*
X654331Y-283858D02*
D03*
X650000D02*
D03*
X646457D02*
D03*
X588189Y-263386D02*
D03*
X637008Y-238583D02*
D03*
X608661Y-242126D02*
D03*
X590551Y-242520D02*
D03*
X547244Y-203150D02*
D03*
X581496Y-198819D02*
D03*
X545276Y-275197D02*
D03*
Y-270866D02*
D03*
X473228Y-105905D02*
D03*
X518337Y-159634D02*
D03*
X515702Y-162803D02*
D03*
X498693Y-188351D02*
D03*
X498819Y-183858D02*
D03*
X499111Y-179528D02*
D03*
X658114Y-56714D02*
D03*
X657445Y-63525D02*
D03*
X658053Y-71188D02*
D03*
X623511Y-62552D02*
D03*
X623228Y-55118D02*
D03*
X64173Y-42520D02*
D03*
X325984Y-272441D02*
D03*
X416835Y-196581D02*
D03*
X411811Y-196850D02*
D03*
X570866Y-70472D02*
D03*
Y-72441D02*
D03*
Y-74410D02*
D03*
X574016Y-70472D02*
D03*
Y-72441D02*
D03*
Y-74410D02*
D03*
X378740Y-127165D02*
D03*
X375532Y-123610D02*
D03*
X314658Y-244775D02*
D03*
X288583Y-225590D02*
D03*
X288189Y-228740D02*
D03*
Y-231102D02*
D03*
X288057Y-233478D02*
D03*
X288057Y-245095D02*
D03*
X288189Y-247638D02*
D03*
X377165Y-107283D02*
D03*
X383465Y-107480D02*
D03*
X375590Y-127165D02*
D03*
X380339Y-107321D02*
D03*
X360236Y-268586D02*
D03*
X26495Y-8991D02*
D03*
X512657Y-270462D02*
D03*
X361811Y-207087D02*
D03*
X361417Y-203150D02*
D03*
X326969Y-197573D02*
D03*
X326966Y-195171D02*
D03*
X366535Y-202362D02*
D03*
X358661Y-194488D02*
D03*
X634252Y-314567D02*
D03*
X653150Y-314567D02*
D03*
X509391Y-350636D02*
D03*
X508997Y-335675D02*
D03*
X451181Y-324852D02*
D03*
X437795D02*
D03*
X453937D02*
D03*
X440551D02*
D03*
X360204Y-252984D02*
D03*
X377921Y-203740D02*
D03*
X372016Y-200787D02*
D03*
X379921Y-201740D02*
D03*
X102528Y-211583D02*
D03*
X97125Y-219488D02*
D03*
X99410Y-216535D02*
D03*
X101378Y-214567D02*
D03*
X86614Y-175197D02*
D03*
X360236Y-262186D02*
D03*
Y-266186D02*
D03*
X86614Y-221457D02*
D03*
X427165Y-175246D02*
D03*
X47244Y-8858D02*
D03*
X40354D02*
D03*
X33465D02*
D03*
X82677Y-232283D02*
D03*
X75787Y-285433D02*
D03*
X87598Y-281496D02*
D03*
X74803Y-179134D02*
D03*
X86562Y-169257D02*
D03*
X80709Y-180118D02*
D03*
X89567Y-140270D02*
D03*
X87254Y-139629D02*
D03*
X463551Y-116025D02*
D03*
X658465Y-37647D02*
D03*
X625000Y-21899D02*
D03*
X314961Y-118947D02*
D03*
X309016Y-128659D02*
D03*
X418898Y-144143D02*
D03*
X416106Y-144180D02*
D03*
X398568Y-145083D02*
D03*
X246339Y-386975D02*
D03*
X249410Y-387253D02*
D03*
X232480D02*
D03*
X229331D02*
D03*
X436221Y-306742D02*
D03*
X212795Y-387253D02*
D03*
X433465Y-306742D02*
D03*
X215945Y-387253D02*
D03*
X262006Y-387255D02*
D03*
X448032Y-306742D02*
D03*
X265158Y-387253D02*
D03*
X445276Y-306742D02*
D03*
X104528Y-92175D02*
D03*
X456742Y-116043D02*
D03*
X464328Y-146397D02*
D03*
X461319Y-143750D02*
D03*
X512402Y-261958D02*
D03*
Y-265108D02*
D03*
X512543Y-268065D02*
D03*
X404823Y-175344D02*
D03*
X402264D02*
D03*
X309016Y-113986D02*
D03*
X193898Y-115009D02*
D03*
Y-119931D02*
D03*
X309055Y-123868D02*
D03*
M02*
